(kicad_pcb
	(version 20260206)
	(generator "pcbnew")
	(generator_version "10.0")
	(general
		(thickness 1.6)
		(legacy_teardrops no)
	)
	(paper "A4")
	(title_block
		(title "12092022_DA0F0TMDCD0_F0T_Management_Board_D_brd_V3_OCP.brd")
		(comment 1 "Grand Teton / footprints 116-120 of 1440")
	)
	(layers
		(0 "F.Cu" signal "TOP")
		(4 "In1.Cu" signal "GND")
		(6 "In2.Cu" signal "IN1")
		(8 "In3.Cu" signal "GND1")
		(10 "In4.Cu" signal "IN2")
		(12 "In5.Cu" signal "VCC")
		(14 "In6.Cu" signal "VCC1")
		(16 "In7.Cu" signal "IN3")
		(18 "In8.Cu" signal "GND2")
		(20 "In9.Cu" signal "IN4")
		(22 "In10.Cu" signal "GND3")
		(2 "B.Cu" signal "BOTTOM")
		(9 "F.Adhes" user "F.Adhesive")
		(11 "B.Adhes" user "B.Adhesive")
		(13 "F.Paste" user "Package Geometry/Pastemask Top")
		(15 "B.Paste" user "Package Geometry/Pastemask Bottom")
		(5 "F.SilkS" user "Ref Des/Silkscreen Top")
		(7 "B.SilkS" user "Ref Des/Silkscreen Bottom")
		(1 "F.Mask" user "Board Geometry/Soldermask Top")
		(3 "B.Mask" user "Board Geometry/Soldermask Bottom")
		(17 "Dwgs.User" user "User.Drawings")
		(19 "Cmts.User" user "User.Comments")
		(21 "Eco1.User" user "User.Eco1")
		(23 "Eco2.User" user "User.Eco2")
		(25 "Edge.Cuts" user "Board Geometry/Outline")
		(27 "Margin" user)
		(31 "F.CrtYd" user "Package Geometry/Place Bound Top")
		(29 "B.CrtYd" user "Package Geometry/Place Bound Bottom")
		(35 "F.Fab" user "Ref Des/Assembly Top")
		(33 "B.Fab" user "Ref Des/Assembly Bottom")
	)
	(footprint ""
		(layer "F.Cu")
		(at 19.320002 -32.312356 -90)
		(property "Reference" "PU42"
			(at -0.174244 -3.007868 90)
			(unlocked yes)
			(layer "F.SilkS")
			(effects
				(font
					(size 0.7874 0.5842)
					(thickness 0.1524)
				)
				(justify left)
			)
		)
		(property "Value" ""
			(at 0 0 270)
			(layer "F.Fab")
			(effects
				(font
					(size 1.27 1.27)
				)
			)
		)
		(duplicate_pad_numbers_are_jumpers no)
		(fp_line
			(start -1.050036 1.549908)
			(end -1.016 1.549908)
			(stroke
				(width 0.1524)
				(type default)
			)
			(layer "F.SilkS")
		)
		(fp_line
			(start 1.016 1.549908)
			(end 1.050036 1.549908)
			(stroke
				(width 0.1524)
				(type default)
			)
			(layer "F.SilkS")
		)
		(fp_line
			(start 1.050036 1.549908)
			(end 1.050036 0.762)
			(stroke
				(width 0.1524)
				(type default)
			)
			(layer "F.SilkS")
		)
		(fp_line
			(start -1.050036 0.762)
			(end -1.050036 1.549908)
			(stroke
				(width 0.1524)
				(type default)
			)
			(layer "F.SilkS")
		)
		(fp_line
			(start -1.050036 -0.2286)
			(end -1.050036 0.2286)
			(stroke
				(width 0.1524)
				(type default)
			)
			(layer "F.SilkS")
		)
		(fp_line
			(start 1.050036 -0.762)
			(end 1.050036 -1.549908)
			(stroke
				(width 0.1524)
				(type default)
			)
			(layer "F.SilkS")
		)
		(fp_line
			(start -1.050036 -1.549908)
			(end -1.050036 -0.762)
			(stroke
				(width 0.1524)
				(type default)
			)
			(layer "F.SilkS")
		)
		(fp_line
			(start -1.016 -1.549908)
			(end -1.050036 -1.549908)
			(stroke
				(width 0.1524)
				(type default)
			)
			(layer "F.SilkS")
		)
		(fp_line
			(start 1.050036 -1.549908)
			(end 1.016 -1.549908)
			(stroke
				(width 0.1524)
				(type default)
			)
			(layer "F.SilkS")
		)
		(fp_poly
			(pts
				(xy -1.52908 -1.280668) (xy -1.373124 -0.813054) (xy -1.840484 -0.96901)
			)
			(stroke
				(width 0)
				(type default)
			)
			(fill yes)
			(layer "F.SilkS")
		)
		(fp_line
			(start -1.050036 1.549908)
			(end 1.050036 1.549908)
			(stroke
				(width 0.1)
				(type default)
			)
			(layer "F.Fab")
		)
		(fp_line
			(start 1.050036 1.549908)
			(end 1.050036 -1.549908)
			(stroke
				(width 0.1)
				(type default)
			)
			(layer "F.Fab")
		)
		(fp_line
			(start -1.050036 -1.549908)
			(end -1.050036 1.549908)
			(stroke
				(width 0.1)
				(type default)
			)
			(layer "F.Fab")
		)
		(fp_line
			(start 1.050036 -1.549908)
			(end -1.050036 -1.549908)
			(stroke
				(width 0.1)
				(type default)
			)
			(layer "F.Fab")
		)
		(fp_poly
			(pts
				(xy -1.851914 -0.720344) (xy -1.411224 -0.499872) (xy -1.851914 -0.279654)
			)
			(stroke
				(width 0)
				(type default)
			)
			(fill yes)
			(layer "F.Fab")
		)
		(pad "1" smd rect
			(at -0.54991 -0.499872)
			(size 0.254 1.4986)
			(layers "F.Cu" "F.Mask" "F.Paste")
			(net "SW_P1V0_AUX_FLT")
		)
		(pad "2" smd rect
			(at -0.54991 0.499872)
			(size 0.254 1.4986)
			(layers "F.Cu" "F.Mask" "F.Paste")
			(net "GND")
		)
		(pad "3" smd rect
			(at -0.750062 1.450086 270)
			(size 0.254 0.7112)
			(layers "F.Cu" "F.Mask" "F.Paste")
			(net "P1V0_AUX_VCC")
		)
		(pad "4" smd rect
			(at -0.249936 1.450086 270)
			(size 0.254 0.7112)
			(layers "F.Cu" "F.Mask" "F.Paste")
			(net "GND")
		)
		(pad "5" smd rect
			(at 0.249936 1.450086 270)
			(size 0.254 0.7112)
			(layers "F.Cu" "F.Mask" "F.Paste")
			(net "EN_P1V0_AUX_R")
		)
		(pad "6" smd rect
			(at 0.750062 1.450086 270)
			(size 0.254 0.7112)
			(layers "F.Cu" "F.Mask" "F.Paste")
			(net "P1V0_AUX_VCC")
		)
		(pad "7" smd rect
			(at 0.94996 0.499872)
			(size 0.254 0.7112)
			(layers "F.Cu" "F.Mask" "F.Paste")
			(net "P1V0_AUX_MODE")
		)
		(pad "8" smd rect
			(at 0.54991 0)
			(size 0.254 1.4986)
			(layers "F.Cu" "F.Mask" "F.Paste")
			(net "SW_P1V0_AUX_SW")
		)
		(pad "9" smd rect
			(at 0.94996 -0.499872)
			(size 0.254 0.7112)
			(layers "F.Cu" "F.Mask" "F.Paste")
			(net "SW_P1V0_AUX_BST")
		)
		(pad "10" smd rect
			(at 0.750062 -1.450086 270)
			(size 0.254 0.7112)
			(layers "F.Cu" "F.Mask" "F.Paste")
			(net "P1V0_AUX_VCC")
		)
		(pad "11" smd rect
			(at 0.249936 -1.450086 270)
			(size 0.254 0.7112)
			(layers "F.Cu" "F.Mask" "F.Paste")
			(net "GND")
		)
		(pad "12" smd rect
			(at -0.249936 -1.450086 270)
			(size 0.254 0.7112)
			(layers "F.Cu" "F.Mask" "F.Paste")
			(net "P1V0_AUX")
		)
		(pad "13" smd rect
			(at -0.750062 -1.450086 270)
			(size 0.254 0.7112)
			(layers "F.Cu" "F.Mask" "F.Paste")
			(net "PWRGD_P1V0_AUX_R")
		)
	)
	(footprint ""
		(layer "F.Cu")
		(at 17.5768 -46.3042 90)
		(property "Reference" "R827"
			(at 0 0 90)
			(layer "F.SilkS")
			(hide yes)
			(effects
				(font
					(size 1.27 1.27)
				)
			)
		)
		(property "Value" ""
			(at 0 0 90)
			(layer "F.Fab")
			(effects
				(font
					(size 1.27 1.27)
				)
			)
		)
		(duplicate_pad_numbers_are_jumpers no)
		(fp_line
			(start 0.7874 -0.4064)
			(end 0.7874 0.4064)
			(stroke
				(width 0.1524)
				(type default)
			)
			(layer "F.SilkS")
		)
		(fp_line
			(start -0.7874 -0.4064)
			(end 0.7874 -0.4064)
			(stroke
				(width 0.1524)
				(type default)
			)
			(layer "F.SilkS")
		)
		(fp_line
			(start 0.7874 0.4064)
			(end -0.7874 0.4064)
			(stroke
				(width 0.1524)
				(type default)
			)
			(layer "F.SilkS")
		)
		(fp_line
			(start -0.7874 0.4064)
			(end -0.7874 -0.4064)
			(stroke
				(width 0.1524)
				(type default)
			)
			(layer "F.SilkS")
		)
		(fp_line
			(start -0.12065 -0.305054)
			(end -0.12065 -0.2794)
			(stroke
				(width 0.1)
				(type default)
			)
			(layer "F.Fab")
		)
		(fp_line
			(start -0.67945 -0.305054)
			(end -0.12065 -0.305054)
			(stroke
				(width 0.1)
				(type default)
			)
			(layer "F.Fab")
		)
		(fp_line
			(start 0.67945 -0.3048)
			(end 0.67945 0.3048)
			(stroke
				(width 0.1)
				(type default)
			)
			(layer "F.Fab")
		)
		(fp_line
			(start 0.12065 -0.3048)
			(end 0.67945 -0.3048)
			(stroke
				(width 0.1)
				(type default)
			)
			(layer "F.Fab")
		)
		(fp_line
			(start 0.12065 -0.2794)
			(end 0.12065 -0.3048)
			(stroke
				(width 0.1)
				(type default)
			)
			(layer "F.Fab")
		)
		(fp_line
			(start -0.12065 -0.2794)
			(end 0.12065 -0.2794)
			(stroke
				(width 0.1)
				(type default)
			)
			(layer "F.Fab")
		)
		(fp_line
			(start 0.120396 0.2794)
			(end -0.12065 0.2794)
			(stroke
				(width 0.1)
				(type default)
			)
			(layer "F.Fab")
		)
		(fp_line
			(start -0.12065 0.2794)
			(end -0.12065 0.3048)
			(stroke
				(width 0.1)
				(type default)
			)
			(layer "F.Fab")
		)
		(fp_line
			(start 0.67945 0.3048)
			(end 0.120396 0.3048)
			(stroke
				(width 0.1)
				(type default)
			)
			(layer "F.Fab")
		)
		(fp_line
			(start 0.120396 0.3048)
			(end 0.120396 0.2794)
			(stroke
				(width 0.1)
				(type default)
			)
			(layer "F.Fab")
		)
		(fp_line
			(start -0.12065 0.3048)
			(end -0.67945 0.3048)
			(stroke
				(width 0.1)
				(type default)
			)
			(layer "F.Fab")
		)
		(fp_line
			(start -0.67945 0.3048)
			(end -0.67945 -0.305054)
			(stroke
				(width 0.1)
				(type default)
			)
			(layer "F.Fab")
		)
		(pad "1" smd circle
			(at -0.40005 0 90)
			(size 0 0)
			(layers "F.Cu" "F.Mask" "F.Paste")
			(net "RST_SPI_FLASH_BUF_R3_N")
		)
		(pad "2" smd circle
			(at 0.40005 0 90)
			(size 0 0)
			(layers "F.Cu" "F.Mask" "F.Paste")
			(net "RST_SPI_FLASH_BUF_N")
		)
	)
	(footprint ""
		(layer "F.Cu")
		(at 83.952842 -59.047634 -90)
		(property "Reference" "PC256"
			(at 0 0 270)
			(layer "F.SilkS")
			(hide yes)
			(effects
				(font
					(size 1.27 1.27)
				)
			)
		)
		(property "Value" ""
			(at 0 0 270)
			(layer "F.Fab")
			(effects
				(font
					(size 1.27 1.27)
				)
			)
		)
		(duplicate_pad_numbers_are_jumpers no)
		(fp_line
			(start -1.651 0.8382)
			(end -1.651 -0.8382)
			(stroke
				(width 0.1524)
				(type default)
			)
			(layer "F.SilkS")
		)
		(fp_line
			(start 0 0.8382)
			(end 0 -0.8382)
			(stroke
				(width 0.1524)
				(type default)
			)
			(layer "F.SilkS")
		)
		(fp_line
			(start 1.651 0.8382)
			(end -1.651 0.8382)
			(stroke
				(width 0.1524)
				(type default)
			)
			(layer "F.SilkS")
		)
		(fp_line
			(start -1.651 -0.8382)
			(end 1.651 -0.8382)
			(stroke
				(width 0.1524)
				(type default)
			)
			(layer "F.SilkS")
		)
		(fp_line
			(start 1.651 -0.8382)
			(end 1.651 0.8382)
			(stroke
				(width 0.1524)
				(type default)
			)
			(layer "F.SilkS")
		)
		(fp_line
			(start -1.55956 0.7366)
			(end -1.524 0.7366)
			(stroke
				(width 0.1)
				(type default)
			)
			(layer "F.Fab")
		)
		(fp_line
			(start -1.524 0.7366)
			(end 1.524 0.7366)
			(stroke
				(width 0.1)
				(type default)
			)
			(layer "F.Fab")
		)
		(fp_line
			(start 1.524 0.7366)
			(end 1.55956 0.7366)
			(stroke
				(width 0.1)
				(type default)
			)
			(layer "F.Fab")
		)
		(fp_line
			(start 1.55956 0.7366)
			(end 1.55956 -0.7366)
			(stroke
				(width 0.1)
				(type default)
			)
			(layer "F.Fab")
		)
		(fp_line
			(start -1.55956 -0.7366)
			(end -1.55956 0.7366)
			(stroke
				(width 0.1)
				(type default)
			)
			(layer "F.Fab")
		)
		(fp_line
			(start -1.524 -0.7366)
			(end -1.55956 -0.7366)
			(stroke
				(width 0.1)
				(type default)
			)
			(layer "F.Fab")
		)
		(fp_line
			(start 1.524 -0.7366)
			(end -1.524 -0.7366)
			(stroke
				(width 0.1)
				(type default)
			)
			(layer "F.Fab")
		)
		(fp_line
			(start 1.55956 -0.7366)
			(end 1.524 -0.7366)
			(stroke
				(width 0.1)
				(type default)
			)
			(layer "F.Fab")
		)
		(pad "1" smd rect
			(at -0.94996 0 90)
			(size 1.1176 1.3716)
			(layers "F.Cu" "F.Mask" "F.Paste")
			(net "P1V2_AUX")
		)
		(pad "2" smd rect
			(at 0.94996 0 90)
			(size 1.1176 1.3716)
			(layers "F.Cu" "F.Mask" "F.Paste")
			(net "GND")
		)
	)
	(footprint ""
		(layer "F.Cu")
		(at 56.20004 -79.21244 90)
		(property "Reference" "R560"
			(at 0 0 90)
			(layer "F.SilkS")
			(hide yes)
			(effects
				(font
					(size 1.27 1.27)
				)
			)
		)
		(property "Value" ""
			(at 0 0 90)
			(layer "F.Fab")
			(effects
				(font
					(size 1.27 1.27)
				)
			)
		)
		(duplicate_pad_numbers_are_jumpers no)
		(fp_line
			(start 0.7874 -0.4064)
			(end 0.7874 0.4064)
			(stroke
				(width 0.1524)
				(type default)
			)
			(layer "F.SilkS")
		)
		(fp_line
			(start -0.7874 -0.4064)
			(end 0.7874 -0.4064)
			(stroke
				(width 0.1524)
				(type default)
			)
			(layer "F.SilkS")
		)
		(fp_line
			(start 0.7874 0.4064)
			(end -0.7874 0.4064)
			(stroke
				(width 0.1524)
				(type default)
			)
			(layer "F.SilkS")
		)
		(fp_line
			(start -0.7874 0.4064)
			(end -0.7874 -0.4064)
			(stroke
				(width 0.1524)
				(type default)
			)
			(layer "F.SilkS")
		)
		(fp_line
			(start -0.12065 -0.305054)
			(end -0.12065 -0.2794)
			(stroke
				(width 0.1)
				(type default)
			)
			(layer "F.Fab")
		)
		(fp_line
			(start -0.67945 -0.305054)
			(end -0.12065 -0.305054)
			(stroke
				(width 0.1)
				(type default)
			)
			(layer "F.Fab")
		)
		(fp_line
			(start 0.67945 -0.3048)
			(end 0.67945 0.3048)
			(stroke
				(width 0.1)
				(type default)
			)
			(layer "F.Fab")
		)
		(fp_line
			(start 0.12065 -0.3048)
			(end 0.67945 -0.3048)
			(stroke
				(width 0.1)
				(type default)
			)
			(layer "F.Fab")
		)
		(fp_line
			(start 0.12065 -0.2794)
			(end 0.12065 -0.3048)
			(stroke
				(width 0.1)
				(type default)
			)
			(layer "F.Fab")
		)
		(fp_line
			(start -0.12065 -0.2794)
			(end 0.12065 -0.2794)
			(stroke
				(width 0.1)
				(type default)
			)
			(layer "F.Fab")
		)
		(fp_line
			(start 0.120396 0.2794)
			(end -0.12065 0.2794)
			(stroke
				(width 0.1)
				(type default)
			)
			(layer "F.Fab")
		)
		(fp_line
			(start -0.12065 0.2794)
			(end -0.12065 0.3048)
			(stroke
				(width 0.1)
				(type default)
			)
			(layer "F.Fab")
		)
		(fp_line
			(start 0.67945 0.3048)
			(end 0.120396 0.3048)
			(stroke
				(width 0.1)
				(type default)
			)
			(layer "F.Fab")
		)
		(fp_line
			(start 0.120396 0.3048)
			(end 0.120396 0.2794)
			(stroke
				(width 0.1)
				(type default)
			)
			(layer "F.Fab")
		)
		(fp_line
			(start -0.12065 0.3048)
			(end -0.67945 0.3048)
			(stroke
				(width 0.1)
				(type default)
			)
			(layer "F.Fab")
		)
		(fp_line
			(start -0.67945 0.3048)
			(end -0.67945 -0.305054)
			(stroke
				(width 0.1)
				(type default)
			)
			(layer "F.Fab")
		)
		(pad "1" smd circle
			(at -0.40005 0 90)
			(size 0 0)
			(layers "F.Cu" "F.Mask" "F.Paste")
			(net "FLASH_LATCH_Q_N_R1")
		)
		(pad "2" smd circle
			(at 0.40005 0 90)
			(size 0 0)
			(layers "F.Cu" "F.Mask" "F.Paste")
			(net "FLASH_LATCH_Q_N_R2")
		)
	)
	(footprint ""
		(layer "F.Cu")
		(at 30.607 -10.287 90)
		(property "Reference" "R43"
			(at 0 0 90)
			(layer "F.SilkS")
			(hide yes)
			(effects
				(font
					(size 1.27 1.27)
				)
			)
		)
		(property "Value" ""
			(at 0 0 90)
			(layer "F.Fab")
			(effects
				(font
					(size 1.27 1.27)
				)
			)
		)
		(duplicate_pad_numbers_are_jumpers no)
		(fp_line
			(start 0.7874 -0.4064)
			(end 0.7874 0.4064)
			(stroke
				(width 0.1524)
				(type default)
			)
			(layer "F.SilkS")
		)
		(fp_line
			(start -0.7874 -0.4064)
			(end 0.7874 -0.4064)
			(stroke
				(width 0.1524)
				(type default)
			)
			(layer "F.SilkS")
		)
		(fp_line
			(start 0.7874 0.4064)
			(end -0.7874 0.4064)
			(stroke
				(width 0.1524)
				(type default)
			)
			(layer "F.SilkS")
		)
		(fp_line
			(start -0.7874 0.4064)
			(end -0.7874 -0.4064)
			(stroke
				(width 0.1524)
				(type default)
			)
			(layer "F.SilkS")
		)
		(fp_line
			(start -0.12065 -0.305054)
			(end -0.12065 -0.2794)
			(stroke
				(width 0.1)
				(type default)
			)
			(layer "F.Fab")
		)
		(fp_line
			(start -0.67945 -0.305054)
			(end -0.12065 -0.305054)
			(stroke
				(width 0.1)
				(type default)
			)
			(layer "F.Fab")
		)
		(fp_line
			(start 0.67945 -0.3048)
			(end 0.67945 0.3048)
			(stroke
				(width 0.1)
				(type default)
			)
			(layer "F.Fab")
		)
		(fp_line
			(start 0.12065 -0.3048)
			(end 0.67945 -0.3048)
			(stroke
				(width 0.1)
				(type default)
			)
			(layer "F.Fab")
		)
		(fp_line
			(start 0.12065 -0.2794)
			(end 0.12065 -0.3048)
			(stroke
				(width 0.1)
				(type default)
			)
			(layer "F.Fab")
		)
		(fp_line
			(start -0.12065 -0.2794)
			(end 0.12065 -0.2794)
			(stroke
				(width 0.1)
				(type default)
			)
			(layer "F.Fab")
		)
		(fp_line
			(start 0.120396 0.2794)
			(end -0.12065 0.2794)
			(stroke
				(width 0.1)
				(type default)
			)
			(layer "F.Fab")
		)
		(fp_line
			(start -0.12065 0.2794)
			(end -0.12065 0.3048)
			(stroke
				(width 0.1)
				(type default)
			)
			(layer "F.Fab")
		)
		(fp_line
			(start 0.67945 0.3048)
			(end 0.120396 0.3048)
			(stroke
				(width 0.1)
				(type default)
			)
			(layer "F.Fab")
		)
		(fp_line
			(start 0.120396 0.3048)
			(end 0.120396 0.2794)
			(stroke
				(width 0.1)
				(type default)
			)
			(layer "F.Fab")
		)
		(fp_line
			(start -0.12065 0.3048)
			(end -0.67945 0.3048)
			(stroke
				(width 0.1)
				(type default)
			)
			(layer "F.Fab")
		)
		(fp_line
			(start -0.67945 0.3048)
			(end -0.67945 -0.305054)
			(stroke
				(width 0.1)
				(type default)
			)
			(layer "F.Fab")
		)
		(pad "1" smd circle
			(at -0.40005 0 90)
			(size 0 0)
			(layers "F.Cu" "F.Mask" "F.Paste")
			(net "ID_LED_P3V3_AUX")
		)
		(pad "2" smd circle
			(at 0.40005 0 90)
			(size 0 0)
			(layers "F.Cu" "F.Mask" "F.Paste")
			(net "P3V3_AUX")
		)
	)
)
